# S9S_MB_2U (Grand Teton) — schematic netlist excerpt (pin names and nets, part order shuffled) for the footprints in the layout excerpt that follows; sources: Cadence DE-HDL packaged netlist, KiCad conversion of 03242023_DA0F0TMBIJ0_F0T_Motherboard_J_brd_V01_OCP.brd

PC188  Q_CAP  2.2UF 10V 10% X6S  pkg C0402  page 275 : A = PVCCINFAON_CPU0_VDD2 ; B = GND
PC2366  Q_CAP  0.1UF 25V 10% EMPTY  pkg 0402  page 284 : A = PVCCIN_CPU1_VCC ; B = GND

(kicad_pcb
	(version 20260206)
	(generator "pcbnew")
	(generator_version "10.0")
	(general
		(thickness 1.6)
		(legacy_teardrops no)
	)
	(paper "A4")
	(title_block
		(title "03242023_DA0F0TMBIJ0_F0T_Motherboard_J_brd_V01_OCP.brd")
		(comment 1 "Grand Teton / footprints 2298-2299 of 6105")
	)
	(layers
		(0 "F.Cu" signal "TOP")
		(4 "In1.Cu" signal "GND")
		(6 "In2.Cu" signal "IN1")
		(8 "In3.Cu" signal "GND1")
		(10 "In4.Cu" signal "IN2")
		(12 "In5.Cu" signal "GND2")
		(14 "In6.Cu" signal "IN3")
		(16 "In7.Cu" signal "GND3")
		(18 "In8.Cu" signal "VCC")
		(20 "In9.Cu" signal "VCC1")
		(22 "In10.Cu" signal "GND4")
		(24 "In11.Cu" signal "IN4")
		(26 "In12.Cu" signal "GND5")
		(28 "In13.Cu" signal "IN5")
		(30 "In14.Cu" signal "GND6")
		(32 "In15.Cu" signal "IN6")
		(34 "In16.Cu" signal "GND7")
		(2 "B.Cu" signal "BOTTOM")
		(9 "F.Adhes" user "F.Adhesive")
		(11 "B.Adhes" user "B.Adhesive")
		(13 "F.Paste" user "Package Geometry/Pastemask Top")
		(15 "B.Paste" user "Package Geometry/Pastemask Bottom")
		(5 "F.SilkS" user "Ref Des/Silkscreen Top")
		(7 "B.SilkS" user "Ref Des/Silkscreen Bottom")
		(1 "F.Mask" user "Board Geometry/Soldermask Top")
		(3 "B.Mask" user "Board Geometry/Soldermask Bottom")
		(17 "Dwgs.User" user "User.Drawings")
		(19 "Cmts.User" user "User.Comments")
		(21 "Eco1.User" user "User.Eco1")
		(23 "Eco2.User" user "User.Eco2")
		(25 "Edge.Cuts" user "Board Geometry/Outline")
		(27 "Margin" user)
		(31 "F.CrtYd" user "Package Geometry/Place Bound Top")
		(29 "B.CrtYd" user "Package Geometry/Place Bound Bottom")
		(35 "F.Fab" user "Ref Des/Assembly Top")
		(33 "B.Fab" user "Ref Des/Assembly Bottom")
	)
	(footprint ""
		(layer "F.Cu")
		(at 114.70386 -363.508036)
		(property "Reference" "PC2366"
			(at 0 0 0)
			(layer "F.SilkS")
			(hide yes)
			(effects
				(font
					(size 1.27 1.27)
				)
			)
		)
		(property "Value" ""
			(at 0 0 0)
			(layer "F.Fab")
			(effects
				(font
					(size 1.27 1.27)
				)
			)
		)
		(duplicate_pad_numbers_are_jumpers no)
		(fp_line
			(start -0.7874 -0.4064)
			(end 0.7874 -0.4064)
			(stroke
				(width 0.1524)
				(type default)
			)
			(layer "F.SilkS")
		)
		(fp_line
			(start -0.7874 0.4064)
			(end -0.7874 -0.4064)
			(stroke
				(width 0.1524)
				(type default)
			)
			(layer "F.SilkS")
		)
		(fp_line
			(start 0.7874 -0.4064)
			(end 0.7874 0.4064)
			(stroke
				(width 0.1524)
				(type default)
			)
			(layer "F.SilkS")
		)
		(fp_line
			(start 0.7874 0.4064)
			(end -0.7874 0.4064)
			(stroke
				(width 0.1524)
				(type default)
			)
			(layer "F.SilkS")
		)
		(fp_line
			(start -0.67945 -0.305054)
			(end -0.12065 -0.305054)
			(stroke
				(width 0.1)
				(type default)
			)
			(layer "F.Fab")
		)
		(fp_line
			(start -0.67945 0.3048)
			(end -0.67945 -0.305054)
			(stroke
				(width 0.1)
				(type default)
			)
			(layer "F.Fab")
		)
		(fp_line
			(start -0.12065 -0.305054)
			(end -0.12065 -0.2794)
			(stroke
				(width 0.1)
				(type default)
			)
			(layer "F.Fab")
		)
		(fp_line
			(start -0.12065 -0.2794)
			(end 0.12065 -0.2794)
			(stroke
				(width 0.1)
				(type default)
			)
			(layer "F.Fab")
		)
		(fp_line
			(start -0.12065 0.2794)
			(end -0.12065 0.3048)
			(stroke
				(width 0.1)
				(type default)
			)
			(layer "F.Fab")
		)
		(fp_line
			(start -0.12065 0.3048)
			(end -0.67945 0.3048)
			(stroke
				(width 0.1)
				(type default)
			)
			(layer "F.Fab")
		)
		(fp_line
			(start 0.120396 0.2794)
			(end -0.12065 0.2794)
			(stroke
				(width 0.1)
				(type default)
			)
			(layer "F.Fab")
		)
		(fp_line
			(start 0.120396 0.3048)
			(end 0.120396 0.2794)
			(stroke
				(width 0.1)
				(type default)
			)
			(layer "F.Fab")
		)
		(fp_line
			(start 0.12065 -0.3048)
			(end 0.67945 -0.3048)
			(stroke
				(width 0.1)
				(type default)
			)
			(layer "F.Fab")
		)
		(fp_line
			(start 0.12065 -0.2794)
			(end 0.12065 -0.3048)
			(stroke
				(width 0.1)
				(type default)
			)
			(layer "F.Fab")
		)
		(fp_line
			(start 0.67945 -0.3048)
			(end 0.67945 0.3048)
			(stroke
				(width 0.1)
				(type default)
			)
			(layer "F.Fab")
		)
		(fp_line
			(start 0.67945 0.3048)
			(end 0.120396 0.3048)
			(stroke
				(width 0.1)
				(type default)
			)
			(layer "F.Fab")
		)
		(pad "1" smd circle
			(at -0.40005 0)
			(size 0 0)
			(layers "F.Cu" "F.Mask" "F.Paste")
			(net "PVCCIN_CPU1_VCC")
		)
		(pad "2" smd circle
			(at 0.40005 0)
			(size 0 0)
			(layers "F.Cu" "F.Mask" "F.Paste")
			(net "GND")
		)
	)
	(footprint ""
		(layer "F.Cu")
		(at 418.485828 -183.032654)
		(property "Reference" "PC188"
			(at 0 0 0)
			(layer "F.SilkS")
			(hide yes)
			(effects
				(font
					(size 1.27 1.27)
				)
			)
		)
		(property "Value" ""
			(at 0 0 0)
			(layer "F.Fab")
			(effects
				(font
					(size 1.27 1.27)
				)
			)
		)
		(duplicate_pad_numbers_are_jumpers no)
		(fp_line
			(start -0.7874 -0.4064)
			(end 0.7874 -0.4064)
			(stroke
				(width 0.1524)
				(type default)
			)
			(layer "F.SilkS")
		)
		(fp_line
			(start -0.7874 0.4064)
			(end -0.7874 -0.4064)
			(stroke
				(width 0.1524)
				(type default)
			)
			(layer "F.SilkS")
		)
		(fp_line
			(start 0.7874 -0.4064)
			(end 0.7874 0.4064)
			(stroke
				(width 0.1524)
				(type default)
			)
			(layer "F.SilkS")
		)
		(fp_line
			(start 0.7874 0.4064)
			(end -0.7874 0.4064)
			(stroke
				(width 0.1524)
				(type default)
			)
			(layer "F.SilkS")
		)
		(fp_line
			(start -0.67945 -0.305054)
			(end -0.12065 -0.305054)
			(stroke
				(width 0.1)
				(type default)
			)
			(layer "F.Fab")
		)
		(fp_line
			(start -0.67945 0.3048)
			(end -0.67945 -0.305054)
			(stroke
				(width 0.1)
				(type default)
			)
			(layer "F.Fab")
		)
		(fp_line
			(start -0.12065 -0.305054)
			(end -0.12065 -0.2794)
			(stroke
				(width 0.1)
				(type default)
			)
			(layer "F.Fab")
		)
		(fp_line
			(start -0.12065 -0.2794)
			(end 0.12065 -0.2794)
			(stroke
				(width 0.1)
				(type default)
			)
			(layer "F.Fab")
		)
		(fp_line
			(start -0.12065 0.2794)
			(end -0.12065 0.3048)
			(stroke
				(width 0.1)
				(type default)
			)
			(layer "F.Fab")
		)
		(fp_line
			(start -0.12065 0.3048)
			(end -0.67945 0.3048)
			(stroke
				(width 0.1)
				(type default)
			)
			(layer "F.Fab")
		)
		(fp_line
			(start 0.120396 0.2794)
			(end -0.12065 0.2794)
			(stroke
				(width 0.1)
				(type default)
			)
			(layer "F.Fab")
		)
		(fp_line
			(start 0.120396 0.3048)
			(end 0.120396 0.2794)
			(stroke
				(width 0.1)
				(type default)
			)
			(layer "F.Fab")
		)
		(fp_line
			(start 0.12065 -0.3048)
			(end 0.67945 -0.3048)
			(stroke
				(width 0.1)
				(type default)
			)
			(layer "F.Fab")
		)
		(fp_line
			(start 0.12065 -0.2794)
			(end 0.12065 -0.3048)
			(stroke
				(width 0.1)
				(type default)
			)
			(layer "F.Fab")
		)
		(fp_line
			(start 0.67945 -0.3048)
			(end 0.67945 0.3048)
			(stroke
				(width 0.1)
				(type default)
			)
			(layer "F.Fab")
		)
		(fp_line
			(start 0.67945 0.3048)
			(end 0.120396 0.3048)
			(stroke
				(width 0.1)
				(type default)
			)
			(layer "F.Fab")
		)
		(pad "1" smd circle
			(at -0.40005 0)
			(size 0 0)
			(layers "F.Cu" "F.Mask" "F.Paste")
			(net "PVCCINFAON_CPU0_VDD2")
		)
		(pad "2" smd circle
			(at 0.40005 0)
			(size 0 0)
			(layers "F.Cu" "F.Mask" "F.Paste")
			(net "GND")
		)
	)
)
